# BASEBOARD_FAB2 (Tioga Pass) — schematic netlist excerpt (pin names and nets, part order shuffled) for the footprints in the layout excerpt that follows; sources: Cadence DE-HDL packaged netlist, KiCad conversion of Wiwynn_Tioga_Pass_MB.brd

C25W101  CAP_A  0.1UF 16V 10% X7R  pkg 0402V  page 254 : A = P3V3_STBY ; B = GND
R8G8  RES  0.0 5% CHIP  pkg 0402  page 189 : A = JTAG_BMC_TDI ; B = JTAG_TDI

(kicad_pcb
	(version 20260206)
	(generator "pcbnew")
	(generator_version "10.0")
	(general
		(thickness 1.6)
		(legacy_teardrops no)
	)
	(paper "A4")
	(title_block
		(title "Wiwynn_Tioga_Pass_MB.brd")
		(comment 1 "Tioga Pass / footprints 321-323 of 4770")
	)
	(layers
		(0 "F.Cu" signal "TOP")
		(4 "In1.Cu" signal "L2GND")
		(6 "In2.Cu" signal "L3")
		(8 "In3.Cu" signal "L4GND")
		(10 "In4.Cu" signal "L5")
		(12 "In5.Cu" signal "L6GND")
		(14 "In6.Cu" signal "L7VCC")
		(16 "In7.Cu" signal "L8VCC")
		(18 "In8.Cu" signal "L9GND")
		(20 "In9.Cu" signal "L10")
		(22 "In10.Cu" signal "L11GND")
		(24 "In11.Cu" signal "L12")
		(26 "In12.Cu" signal "L13GND")
		(2 "B.Cu" signal "BOTTOM")
		(9 "F.Adhes" user "F.Adhesive")
		(11 "B.Adhes" user "B.Adhesive")
		(13 "F.Paste" user "Package Geometry/Pastemask Top")
		(15 "B.Paste" user "Package Geometry/Pastemask Bottom")
		(5 "F.SilkS" user "Ref Des/Silkscreen Top")
		(7 "B.SilkS" user "Ref Des/Silkscreen Bottom")
		(1 "F.Mask" user "Board Geometry/Soldermask Top")
		(3 "B.Mask" user "Board Geometry/Soldermask Bottom")
		(17 "Dwgs.User" user "User.Drawings")
		(19 "Cmts.User" user "User.Comments")
		(21 "Eco1.User" user "User.Eco1")
		(23 "Eco2.User" user "User.Eco2")
		(25 "Edge.Cuts" user "Board Geometry/Outline")
		(27 "Margin" user)
		(31 "F.CrtYd" user "Package Geometry/Place Bound Top")
		(29 "B.CrtYd" user "Package Geometry/Place Bound Bottom")
		(35 "F.Fab" user "Ref Des/Assembly Top")
		(33 "B.Fab" user "Ref Des/Assembly Bottom")
	)
	(footprint ""
		(layer "F.Cu")
		(at 388.0104 -0.254)
		(property "Reference" "R8G8"
			(at 0 0 0)
			(layer "F.SilkS")
			(hide yes)
			(effects
				(font
					(size 1.27 1.27)
				)
			)
		)
		(property "Value" ""
			(at 0 0 0)
			(layer "F.Fab")
			(effects
				(font
					(size 1.27 1.27)
				)
			)
		)
		(duplicate_pad_numbers_are_jumpers no)
		(fp_poly
			(pts
				(xy -0.2794 -0.1016) (xy 0.2794 -0.1016) (xy 0.2794 0.9906) (xy -0.2794 0.9906)
			)
			(stroke
				(width 0)
				(type default)
			)
			(fill no)
			(layer "F.CrtYd")
		)
		(fp_line
			(start -0.2794 -0.1016)
			(end -0.2794 0.9906)
			(stroke
				(width 0.1)
				(type default)
			)
			(layer "F.Fab")
		)
		(fp_line
			(start -0.2794 0.9906)
			(end 0.2794 0.9906)
			(stroke
				(width 0.1)
				(type default)
			)
			(layer "F.Fab")
		)
		(fp_line
			(start 0.2794 -0.1016)
			(end -0.2794 -0.1016)
			(stroke
				(width 0.1)
				(type default)
			)
			(layer "F.Fab")
		)
		(fp_line
			(start 0.2794 0.9906)
			(end 0.2794 -0.1016)
			(stroke
				(width 0.1)
				(type default)
			)
			(layer "F.Fab")
		)
		(pad "1" smd rect
			(at 0 0)
			(size 0.508 0.508)
			(layers "F.Cu" "F.Mask" "F.Paste")
			(net "JTAG_BMC_TDI")
		)
		(pad "2" smd rect
			(at 0 0.889)
			(size 0.508 0.508)
			(layers "F.Cu" "F.Mask" "F.Paste")
			(net "JTAG_TDI")
		)
		(zone
			(layer "F.Cu")
			(hatch none 0.5)
			(connect_pads
				(clearance 0)
			)
			(min_thickness 0.25)
			(keepout
				(tracks allowed)
				(vias not_allowed)
				(pads allowed)
				(copperpour not_allowed)
				(footprints allowed)
			)
			(placement
				(enabled no)
				(sheetname "")
			)
			(fill
				(thermal_gap 0.5)
				(thermal_bridge_width 0.5)
				(island_removal_mode 0)
			)
			(polygon
				(pts
					(xy 387.7564 0) (xy 388.2644 0) (xy 388.2644 0.381) (xy 387.7564 0.381)
				)
			)
		)
		(zone
			(layer "F.Cu")
			(hatch none 0.5)
			(connect_pads
				(clearance 0)
			)
			(min_thickness 0.25)
			(keepout
				(tracks not_allowed)
				(vias allowed)
				(pads allowed)
				(copperpour not_allowed)
				(footprints allowed)
			)
			(placement
				(enabled no)
				(sheetname "")
			)
			(fill
				(thermal_gap 0.5)
				(thermal_bridge_width 0.5)
				(island_removal_mode 0)
			)
			(polygon
				(pts
					(xy 387.7564 0.381) (xy 388.2644 0.381) (xy 388.2644 0) (xy 387.7564 0)
				)
			)
		)
	)
	(footprint ""
		(layer "F.Cu")
		(at 441.404756 -147.621244 90)
		(property "Reference" "C25W101"
			(at -0.8382 -0.67818 90)
			(unlocked yes)
			(layer "F.SilkS")
			(effects
				(font
					(size 0.4064 0.254)
					(thickness 0.1524)
				)
				(justify left)
			)
		)
		(property "Value" ""
			(at 0 0 90)
			(layer "F.Fab")
			(effects
				(font
					(size 1.27 1.27)
				)
			)
		)
		(duplicate_pad_numbers_are_jumpers no)
		(fp_poly
			(pts
				(xy 0.3048 -0.1016) (xy 0.3048 0.9906) (xy -0.3048 0.9906) (xy -0.3048 -0.1016)
			)
			(stroke
				(width 0)
				(type default)
			)
			(fill no)
			(layer "F.CrtYd")
		)
		(fp_line
			(start 0.3048 -0.1016)
			(end -0.3048 -0.1016)
			(stroke
				(width 0.1)
				(type default)
			)
			(layer "F.Fab")
		)
		(fp_line
			(start -0.3048 -0.1016)
			(end -0.3048 0.9906)
			(stroke
				(width 0.1)
				(type default)
			)
			(layer "F.Fab")
		)
		(fp_line
			(start 0.3048 0.9906)
			(end 0.3048 -0.1016)
			(stroke
				(width 0.1)
				(type default)
			)
			(layer "F.Fab")
		)
		(fp_line
			(start -0.3048 0.9906)
			(end 0.3048 0.9906)
			(stroke
				(width 0.1)
				(type default)
			)
			(layer "F.Fab")
		)
		(pad "1" smd rect
			(at 0 0 90)
			(size 0.508 0.508)
			(layers "F.Cu" "F.Mask" "F.Paste")
			(net "P3V3_STBY")
		)
		(pad "2" smd rect
			(at 0 0.889 90)
			(size 0.508 0.508)
			(layers "F.Cu" "F.Mask" "F.Paste")
			(net "GND")
		)
		(zone
			(layer "F.Cu")
			(hatch none 0.5)
			(connect_pads
				(clearance 0)
			)
			(min_thickness 0.25)
			(keepout
				(tracks allowed)
				(vias not_allowed)
				(pads allowed)
				(copperpour not_allowed)
				(footprints allowed)
			)
			(placement
				(enabled no)
				(sheetname "")
			)
			(fill
				(thermal_gap 0.5)
				(thermal_bridge_width 0.5)
				(island_removal_mode 0)
			)
			(polygon
				(pts
					(xy 441.658756 -147.367244) (xy 441.658756 -147.875244) (xy 442.039756 -147.875244) (xy 442.039756 -147.367244)
				)
			)
		)
		(zone
			(layer "F.Cu")
			(hatch none 0.5)
			(connect_pads
				(clearance 0)
			)
			(min_thickness 0.25)
			(keepout
				(tracks not_allowed)
				(vias allowed)
				(pads allowed)
				(copperpour not_allowed)
				(footprints allowed)
			)
			(placement
				(enabled no)
				(sheetname "")
			)
			(fill
				(thermal_gap 0.5)
				(thermal_bridge_width 0.5)
				(island_removal_mode 0)
			)
			(polygon
				(pts
					(xy 442.039756 -147.367244) (xy 442.039756 -147.875244) (xy 441.658756 -147.875244) (xy 441.658756 -147.367244)
				)
			)
		)
	)
	(footprint ""
		(layer "F.Cu")
		(at 182.626 -84.1248)
		(property "Reference" ""
			(at 0 0 0)
			(layer "F.SilkS")
			(hide yes)
			(effects
				(font
					(size 1.27 1.27)
				)
			)
		)
		(property "Value" ""
			(at 0 0 0)
			(layer "F.Fab")
			(effects
				(font
					(size 1.27 1.27)
				)
			)
		)
		(duplicate_pad_numbers_are_jumpers no)
		(fp_poly
			(pts
				(arc
					(start 2.032 0)
					(mid -2.032 0)
					(end 2.032 0)
				)
			)
			(stroke
				(width 0)
				(type default)
			)
			(fill no)
			(layer "F.CrtYd")
		)
		(pad "1" smd circle
			(at 0 0)
			(size 1.016 1.016)
			(layers "F.Cu" "F.Mask" "F.Paste")
			(net "Net_393")
		)
		(zone
			(layer "F.Cu")
			(hatch none 0.5)
			(connect_pads
				(clearance 0)
			)
			(min_thickness 0.25)
			(keepout
				(tracks not_allowed)
				(vias allowed)
				(pads allowed)
				(copperpour not_allowed)
				(footprints allowed)
			)
			(placement
				(enabled no)
				(sheetname "")
			)
			(fill
				(thermal_gap 0.5)
				(thermal_bridge_width 0.5)
				(island_removal_mode 0)
			)
			(polygon
				(pts
					(arc
						(start 184.15 -84.1248)
						(mid 181.102 -84.1248)
						(end 184.15 -84.1248)
					)
				)
			)
		)
		(zone
			(layers "F.Cu" "B.Cu" "In1.Cu" "In2.Cu" "In3.Cu" "In4.Cu" "In5.Cu" "In6.Cu"
				"In7.Cu" "In8.Cu" "In9.Cu" "In10.Cu" "In11.Cu" "In12.Cu"
			)
			(hatch none 0.5)
			(connect_pads
				(clearance 0)
			)
			(min_thickness 0.25)
			(keepout
				(tracks allowed)
				(vias not_allowed)
				(pads allowed)
				(copperpour not_allowed)
				(footprints allowed)
			)
			(placement
				(enabled no)
				(sheetname "")
			)
			(fill
				(thermal_gap 0.5)
				(thermal_bridge_width 0.5)
				(island_removal_mode 0)
			)
			(polygon
				(pts
					(arc
						(start 184.15 -84.1248)
						(mid 181.102 -84.1248)
						(end 184.15 -84.1248)
					)
				)
			)
		)
	)
)
